# T6G (Grand Teton) — schematic netlist excerpt (pin names and nets, part order shuffled) for the footprints in the layout excerpt that follows; sources: Cadence DE-HDL packaged netlist, KiCad conversion of 04192023_DAF0TMB3IC0_F0TG_MB_C_brd_V02_OCP.brd

R3097  Q_RES  130 1% CHIP  pkg 0402LF  page 256 : A = LED_PWRGD_PVDD18_S5_P1_R ; B = P3V3_AUX
R8304  Q_RES  49.9 1% CHIP  pkg 0402LF  page 193 : A = SVID_PVDDCR_CPU0_P0_SVTO ; B = SVID_PVDDCR_CPU0_P0_SVTO_R
PC154_1  Q_CAP  22UF 16V 20% X6S  pkg C0805  page 205 : A = SW_P12V_AUX_PVDDIO_P0_FLT ; B = GND

(kicad_pcb
	(version 20260206)
	(generator "pcbnew")
	(generator_version "10.0")
	(general
		(thickness 1.6)
		(legacy_teardrops no)
	)
	(paper "A4")
	(title_block
		(title "04192023_DAF0TMB3IC0_F0TG_MB_C_brd_V02_OCP.brd")
		(comment 1 "Grand Teton / footprints 5839-5841 of 8354")
	)
	(layers
		(0 "F.Cu" signal "TOP")
		(4 "In1.Cu" signal "GND")
		(6 "In2.Cu" signal "IN1")
		(8 "In3.Cu" signal "GND1")
		(10 "In4.Cu" signal "IN2")
		(12 "In5.Cu" signal "GND2")
		(14 "In6.Cu" signal "IN3")
		(16 "In7.Cu" signal "GND3")
		(18 "In8.Cu" signal "VCC")
		(20 "In9.Cu" signal "VCC1")
		(22 "In10.Cu" signal "GND4")
		(24 "In11.Cu" signal "IN4")
		(26 "In12.Cu" signal "GND5")
		(28 "In13.Cu" signal "IN5")
		(30 "In14.Cu" signal "GND6")
		(32 "In15.Cu" signal "IN6")
		(34 "In16.Cu" signal "GND7")
		(2 "B.Cu" signal "BOTTOM")
		(9 "F.Adhes" user "F.Adhesive")
		(11 "B.Adhes" user "B.Adhesive")
		(13 "F.Paste" user "Package Geometry/Pastemask Top")
		(15 "B.Paste" user "Package Geometry/Pastemask Bottom")
		(5 "F.SilkS" user "Ref Des/Silkscreen Top")
		(7 "B.SilkS" user "Ref Des/Silkscreen Bottom")
		(1 "F.Mask" user "Board Geometry/Soldermask Top")
		(3 "B.Mask" user "Board Geometry/Soldermask Bottom")
		(17 "Dwgs.User" user "User.Drawings")
		(19 "Cmts.User" user "User.Comments")
		(21 "Eco1.User" user "User.Eco1")
		(23 "Eco2.User" user "User.Eco2")
		(25 "Edge.Cuts" user "Board Geometry/Outline")
		(27 "Margin" user)
		(31 "F.CrtYd" user "Package Geometry/Place Bound Top")
		(29 "B.CrtYd" user "Package Geometry/Place Bound Bottom")
		(35 "F.Fab" user "Ref Des/Assembly Top")
		(33 "B.Fab" user "Ref Des/Assembly Bottom")
	)
	(footprint ""
		(layer "B.Cu")
		(at 372.937278 -146.552158 180)
		(property "Reference" "R8304"
			(at 0 0 0)
			(layer "B.SilkS")
			(hide yes)
			(effects
				(font
					(size 1.27 1.27)
				)
				(justify mirror)
			)
		)
		(property "Value" ""
			(at 0 0 0)
			(layer "B.Fab")
			(effects
				(font
					(size 1.27 1.27)
				)
				(justify mirror)
			)
		)
		(duplicate_pad_numbers_are_jumpers no)
		(fp_line
			(start 0.7874 0.4064)
			(end 0.7874 -0.4064)
			(stroke
				(width 0.1524)
				(type default)
			)
			(layer "B.SilkS")
		)
		(fp_line
			(start 0.7874 -0.4064)
			(end -0.7874 -0.4064)
			(stroke
				(width 0.1524)
				(type default)
			)
			(layer "B.SilkS")
		)
		(fp_line
			(start -0.7874 0.4064)
			(end 0.7874 0.4064)
			(stroke
				(width 0.1524)
				(type default)
			)
			(layer "B.SilkS")
		)
		(fp_line
			(start -0.7874 -0.4064)
			(end -0.7874 0.4064)
			(stroke
				(width 0.1524)
				(type default)
			)
			(layer "B.SilkS")
		)
		(fp_line
			(start 0.67945 0.3048)
			(end 0.67945 -0.305054)
			(stroke
				(width 0.1)
				(type default)
			)
			(layer "B.Fab")
		)
		(fp_line
			(start 0.67945 -0.305054)
			(end 0.12065 -0.305054)
			(stroke
				(width 0.1)
				(type default)
			)
			(layer "B.Fab")
		)
		(fp_line
			(start 0.12065 0.3048)
			(end 0.67945 0.3048)
			(stroke
				(width 0.1)
				(type default)
			)
			(layer "B.Fab")
		)
		(fp_line
			(start 0.12065 0.2794)
			(end 0.12065 0.3048)
			(stroke
				(width 0.1)
				(type default)
			)
			(layer "B.Fab")
		)
		(fp_line
			(start 0.12065 -0.2794)
			(end -0.12065 -0.2794)
			(stroke
				(width 0.1)
				(type default)
			)
			(layer "B.Fab")
		)
		(fp_line
			(start 0.12065 -0.305054)
			(end 0.12065 -0.2794)
			(stroke
				(width 0.1)
				(type default)
			)
			(layer "B.Fab")
		)
		(fp_line
			(start -0.120396 0.3048)
			(end -0.120396 0.2794)
			(stroke
				(width 0.1)
				(type default)
			)
			(layer "B.Fab")
		)
		(fp_line
			(start -0.120396 0.2794)
			(end 0.12065 0.2794)
			(stroke
				(width 0.1)
				(type default)
			)
			(layer "B.Fab")
		)
		(fp_line
			(start -0.12065 -0.2794)
			(end -0.12065 -0.3048)
			(stroke
				(width 0.1)
				(type default)
			)
			(layer "B.Fab")
		)
		(fp_line
			(start -0.12065 -0.3048)
			(end -0.67945 -0.3048)
			(stroke
				(width 0.1)
				(type default)
			)
			(layer "B.Fab")
		)
		(fp_line
			(start -0.67945 0.3048)
			(end -0.120396 0.3048)
			(stroke
				(width 0.1)
				(type default)
			)
			(layer "B.Fab")
		)
		(fp_line
			(start -0.67945 -0.3048)
			(end -0.67945 0.3048)
			(stroke
				(width 0.1)
				(type default)
			)
			(layer "B.Fab")
		)
		(pad "1" smd circle
			(at 0.40005 0)
			(size 0 0)
			(layers "B.Cu" "B.Mask" "B.Paste")
			(net "SVID_PVDDCR_CPU0_P0_SVTO")
		)
		(pad "2" smd circle
			(at -0.40005 0)
			(size 0 0)
			(layers "B.Cu" "B.Mask" "B.Paste")
			(net "SVID_PVDDCR_CPU0_P0_SVTO_R")
		)
	)
	(footprint ""
		(layer "B.Cu")
		(at 346.987876 -66.708782 90)
		(property "Reference" "R3097"
			(at 0 0 90)
			(layer "B.SilkS")
			(hide yes)
			(effects
				(font
					(size 1.27 1.27)
				)
				(justify mirror)
			)
		)
		(property "Value" ""
			(at 0 0 90)
			(layer "B.Fab")
			(effects
				(font
					(size 1.27 1.27)
				)
				(justify mirror)
			)
		)
		(duplicate_pad_numbers_are_jumpers no)
		(fp_line
			(start 0.7874 -0.4064)
			(end -0.7874 -0.4064)
			(stroke
				(width 0.1524)
				(type default)
			)
			(layer "B.SilkS")
		)
		(fp_line
			(start -0.7874 -0.4064)
			(end -0.7874 0.4064)
			(stroke
				(width 0.1524)
				(type default)
			)
			(layer "B.SilkS")
		)
		(fp_line
			(start 0.7874 0.4064)
			(end 0.7874 -0.4064)
			(stroke
				(width 0.1524)
				(type default)
			)
			(layer "B.SilkS")
		)
		(fp_line
			(start -0.7874 0.4064)
			(end 0.7874 0.4064)
			(stroke
				(width 0.1524)
				(type default)
			)
			(layer "B.SilkS")
		)
		(fp_line
			(start 0.67945 -0.305054)
			(end 0.12065 -0.305054)
			(stroke
				(width 0.1)
				(type default)
			)
			(layer "B.Fab")
		)
		(fp_line
			(start 0.12065 -0.305054)
			(end 0.12065 -0.2794)
			(stroke
				(width 0.1)
				(type default)
			)
			(layer "B.Fab")
		)
		(fp_line
			(start -0.12065 -0.3048)
			(end -0.67945 -0.3048)
			(stroke
				(width 0.1)
				(type default)
			)
			(layer "B.Fab")
		)
		(fp_line
			(start -0.67945 -0.3048)
			(end -0.67945 0.3048)
			(stroke
				(width 0.1)
				(type default)
			)
			(layer "B.Fab")
		)
		(fp_line
			(start 0.12065 -0.2794)
			(end -0.12065 -0.2794)
			(stroke
				(width 0.1)
				(type default)
			)
			(layer "B.Fab")
		)
		(fp_line
			(start -0.12065 -0.2794)
			(end -0.12065 -0.3048)
			(stroke
				(width 0.1)
				(type default)
			)
			(layer "B.Fab")
		)
		(fp_line
			(start 0.12065 0.2794)
			(end 0.12065 0.3048)
			(stroke
				(width 0.1)
				(type default)
			)
			(layer "B.Fab")
		)
		(fp_line
			(start -0.120396 0.2794)
			(end 0.12065 0.2794)
			(stroke
				(width 0.1)
				(type default)
			)
			(layer "B.Fab")
		)
		(fp_line
			(start 0.67945 0.3048)
			(end 0.67945 -0.305054)
			(stroke
				(width 0.1)
				(type default)
			)
			(layer "B.Fab")
		)
		(fp_line
			(start 0.12065 0.3048)
			(end 0.67945 0.3048)
			(stroke
				(width 0.1)
				(type default)
			)
			(layer "B.Fab")
		)
		(fp_line
			(start -0.120396 0.3048)
			(end -0.120396 0.2794)
			(stroke
				(width 0.1)
				(type default)
			)
			(layer "B.Fab")
		)
		(fp_line
			(start -0.67945 0.3048)
			(end -0.120396 0.3048)
			(stroke
				(width 0.1)
				(type default)
			)
			(layer "B.Fab")
		)
		(pad "1" smd circle
			(at 0.40005 0 270)
			(size 0 0)
			(layers "B.Cu" "B.Mask" "B.Paste")
			(net "LED_PWRGD_PVDD18_S5_P1_R")
		)
		(pad "2" smd circle
			(at -0.40005 0 270)
			(size 0 0)
			(layers "B.Cu" "B.Mask" "B.Paste")
			(net "P3V3_AUX")
		)
	)
	(footprint ""
		(layer "B.Cu")
		(at 301.48657 -350.65589 -90)
		(property "Reference" "PC154_1"
			(at 0 0 90)
			(layer "B.SilkS")
			(hide yes)
			(effects
				(font
					(size 1.27 1.27)
				)
				(justify mirror)
			)
		)
		(property "Value" ""
			(at 0 0 90)
			(layer "B.Fab")
			(effects
				(font
					(size 1.27 1.27)
				)
				(justify mirror)
			)
		)
		(duplicate_pad_numbers_are_jumpers no)
		(fp_line
			(start -1.524 0.762)
			(end 1.524 0.762)
			(stroke
				(width 0.1524)
				(type default)
			)
			(layer "B.SilkS")
		)
		(fp_line
			(start 1.524 0.762)
			(end 1.524 -0.762)
			(stroke
				(width 0.1524)
				(type default)
			)
			(layer "B.SilkS")
		)
		(fp_line
			(start -1.524 -0.762)
			(end -1.524 0.762)
			(stroke
				(width 0.1524)
				(type default)
			)
			(layer "B.SilkS")
		)
		(fp_line
			(start 1.524 -0.762)
			(end -1.524 -0.762)
			(stroke
				(width 0.1524)
				(type default)
			)
			(layer "B.SilkS")
		)
		(fp_line
			(start -1.1049 0.724916)
			(end -1.1049 -0.724916)
			(stroke
				(width 0.1)
				(type default)
			)
			(layer "B.Fab")
		)
		(fp_line
			(start 1.1049 0.724916)
			(end -1.1049 0.724916)
			(stroke
				(width 0.1)
				(type default)
			)
			(layer "B.Fab")
		)
		(fp_line
			(start -1.1049 -0.724916)
			(end 1.1049 -0.724916)
			(stroke
				(width 0.1)
				(type default)
			)
			(layer "B.Fab")
		)
		(fp_line
			(start 1.1049 -0.724916)
			(end 1.1049 0.724916)
			(stroke
				(width 0.1)
				(type default)
			)
			(layer "B.Fab")
		)
		(pad "1" smd rect
			(at 0.889 0 270)
			(size 1.016 1.27)
			(layers "B.Cu" "B.Mask" "B.Paste")
			(net "SW_P12V_AUX_PVDDIO_P0_FLT")
		)
		(pad "2" smd rect
			(at -0.889 0 270)
			(size 1.016 1.27)
			(layers "B.Cu" "B.Mask" "B.Paste")
			(net "GND")
		)
	)
)
